FILE_TYPE = MULTI_PHYS_TABLE;

PART 'CONN3_210HP1030BR1'

{========================================================================================}
:VALUE                  | PART_TYPE | MATERIAL | PART_NUMBER    = STANDARD | LIFECYCLE          | PART_NUMBER   | JEDEC_TYPE    | DESCRIPTION                            | MANUFTR | MANUF_PN         | RD_CMPLS_LVL | CMPLS_LVL | CLASS | DIP_SMD | FROM_PJ    | DATA                     | FP_ECN | EE_CHECK_LIST | CREATOR | CREATEDAY  | PSL | STATUS | ESD_CDM | ESD_HBM | ESD_MM | MSD  | PIN_LENGTH_LONG_PIN | PIN_LENGTH_SHORT_PIN ;
{========================================================================================}
 'CONN3_210-HP1-030BR1' | 'THLF'    | 'IO'     | 'DFHD03MS213'(!) = ''       | ''               | 'DFHD03MS213' |'HEADER1X3XG'| 'CONN DIP HEADER 3P 1R MS(P2.54,H8.6)' | 'PRX'   | '210-HP1-030BR1' | 'EP(V1)'     | 'EP(V1)'  | 'IO'  | 'DIP'   | 'F08-OWEN' | 'PRX_210-HP1-030BR1.pdf' | ''     | ''            | ''      | '20160621' | ''  | ''     | 'NA'    | 'NA'    | 'NA'   | 'NA' | '119 MILS'          | '119 MILS'          
 'CONN3_210-HP1-030BR1' | 'THLF'    | 'EMPTY'  | 'DFHD03MS213'(!) = ''       | ''               | 'DFHD03MS213' |'HEADER1X3XG'| 'CONN DIP HEADER 3P 1R MS(P2.54,H8.6)' | 'PRX'   | '210-HP1-030BR1' | 'EP(V1)'     | 'EP(V1)'  | 'IO'  | 'DIP'   | 'F08-OWEN' | 'PRX_210-HP1-030BR1.pdf' | ''     | ''            | ''      | '20160621' | ''  | ''     | 'NA'    | 'NA'    | 'NA'   | 'NA' | '119 MILS'          | '119 MILS'          

END_PART

END.

